# TIMECARD (Time Appliance Project (Time Card)) — schematic netlist excerpt (pin names and nets, part order shuffled) for the footprints in the layout excerpt that follows; sources: Cadence DE-HDL packaged netlist, KiCad conversion of R4006-B0001-02_R01.brd

R347  RESISTOR  0OHM -  pkg SMC_0402R_H016  page 19 : \1\ = UNNAMED_8_ICP10100LGA10_I24_R_2 ; \2\ = XP1R8V_ICP10100
R187  RESISTOR  4.22KOHM 1%  pkg SMC_0402R  page 30 : \1\ = XP1R8V_FPGA ; \2\ = XP1R8V_FB

(kicad_pcb
	(version 20260206)
	(generator "pcbnew")
	(generator_version "10.0")
	(general
		(thickness 1.6)
		(legacy_teardrops no)
	)
	(paper "A4")
	(title_block
		(title "timecard-production-celestica-r4006 — R4006-B0001-02_R01.brd")
		(comment 1 "Time Appliance Project (Time Card) / footprints 405-406 of 1113")
	)
	(layers
		(0 "F.Cu" signal "TOP")
		(4 "In1.Cu" signal "L02_GND1")
		(6 "In2.Cu" signal "L03_SIG1")
		(8 "In3.Cu" signal "L04_GND2")
		(10 "In4.Cu" signal "L05_VCC1")
		(12 "In5.Cu" signal "L06_VCC2")
		(14 "In6.Cu" signal "L07_GND3")
		(16 "In7.Cu" signal "L08_SIG2")
		(18 "In8.Cu" signal "L09_GND4")
		(2 "B.Cu" signal "BOTTOM")
		(9 "F.Adhes" user "F.Adhesive")
		(11 "B.Adhes" user "B.Adhesive")
		(13 "F.Paste" user "Package Geometry/Pastemask Top")
		(15 "B.Paste" user "Package Geometry/Pastemask Bottom")
		(5 "F.SilkS" user "Ref Des/Silkscreen Top")
		(7 "B.SilkS" user "Ref Des/Silkscreen Bottom")
		(1 "F.Mask" user "Board Geometry/Soldermask Top")
		(3 "B.Mask" user "Board Geometry/Soldermask Bottom")
		(17 "Dwgs.User" user "User.Drawings")
		(19 "Cmts.User" user "User.Comments")
		(21 "Eco1.User" user "User.Eco1")
		(23 "Eco2.User" user "User.Eco2")
		(25 "Edge.Cuts" user "Board Geometry/Outline")
		(27 "Margin" user)
		(31 "F.CrtYd" user "Package Geometry/Place Bound Top")
		(29 "B.CrtYd" user "Package Geometry/Place Bound Bottom")
		(35 "F.Fab" user "Ref Des/Assembly Top")
		(33 "B.Fab" user "Ref Des/Assembly Bottom")
	)
	(footprint ""
		(layer "F.Cu")
		(at 134.0612 -66.8528 90)
		(property "Reference" "R187"
			(at -4.8768 0.59817 90)
			(unlocked yes)
			(layer "F.SilkS")
			(effects
				(font
					(size 0.7874 0.5842)
					(thickness 0.1524)
				)
			)
		)
		(property "Value" "VAL*"
			(at 0.0508 2.245106 90)
			(unlocked yes)
			(layer "F.Fab")
			(hide yes)
			(effects
				(font
					(size 0.7874 0.5842)
					(thickness 0.1524)
				)
			)
		)
		(property "User Part Number" "PARTNUM*"
			(at 0.0762 4.302506 90)
			(unlocked yes)
			(layer "Cmts.User")
			(hide yes)
			(effects
				(font
					(size 0.7874 0.5842)
					(thickness 0.1524)
				)
			)
		)
		(property "Device Type" "RESISTOR-G155-04221-01,4.22KOHA"
			(at 0.0762 1.254506 90)
			(unlocked yes)
			(layer "F.Fab")
			(hide yes)
			(effects
				(font
					(size 0.7874 0.5842)
					(thickness 0.1524)
				)
			)
		)
		(property "Tolerance" "TOL*"
			(at 0.0508 3.261106 90)
			(unlocked yes)
			(layer "Cmts.User")
			(hide yes)
			(effects
				(font
					(size 0.7874 0.5842)
					(thickness 0.1524)
				)
			)
		)
		(duplicate_pad_numbers_are_jumpers no)
		(fp_line
			(start 1.143 -0.5588)
			(end -1.143 -0.5588)
			(stroke
				(width 0.1)
				(type default)
			)
			(layer "F.SilkS")
		)
		(fp_line
			(start -1.143 -0.5588)
			(end -1.143 0.5588)
			(stroke
				(width 0.1)
				(type default)
			)
			(layer "F.SilkS")
		)
		(fp_line
			(start 1.143 0.5588)
			(end 1.143 -0.5588)
			(stroke
				(width 0.1)
				(type default)
			)
			(layer "F.SilkS")
		)
		(fp_line
			(start -1.143 0.5588)
			(end 1.143 0.5588)
			(stroke
				(width 0.1)
				(type default)
			)
			(layer "F.SilkS")
		)
		(fp_rect
			(start 1.143 0.5588)
			(end -1.143 -0.5588)
			(stroke
				(width 0)
				(type default)
			)
			(fill no)
			(layer "F.CrtYd")
		)
		(fp_line
			(start 0.508 -0.3048)
			(end -0.508 -0.3048)
			(stroke
				(width 0.1)
				(type default)
			)
			(layer "F.Fab")
		)
		(fp_line
			(start -0.508 -0.3048)
			(end -0.508 0.3048)
			(stroke
				(width 0.1)
				(type default)
			)
			(layer "F.Fab")
		)
		(fp_line
			(start 0.508 0.3048)
			(end 0.508 -0.3048)
			(stroke
				(width 0.1)
				(type default)
			)
			(layer "F.Fab")
		)
		(fp_line
			(start -0.508 0.3048)
			(end 0.508 0.3048)
			(stroke
				(width 0.1)
				(type default)
			)
			(layer "F.Fab")
		)
		(pad "1" smd rect
			(at -0.5334 0 90)
			(size 0.7112 0.6096)
			(layers "F.Cu" "F.Mask" "F.Paste")
			(net "XP1R8V_FPGA")
		)
		(pad "2" smd rect
			(at 0.5334 0 90)
			(size 0.7112 0.6096)
			(layers "F.Cu" "F.Mask" "F.Paste")
			(net "XP1R8V_FB")
		)
		(zone
			(layer "F.Cu")
			(hatch none 0.5)
			(connect_pads
				(clearance 0)
			)
			(min_thickness 0.25)
			(keepout
				(tracks allowed)
				(vias not_allowed)
				(pads allowed)
				(copperpour not_allowed)
				(footprints allowed)
			)
			(placement
				(enabled no)
				(sheetname "")
			)
			(fill
				(thermal_gap 0.5)
				(thermal_bridge_width 0.5)
				(island_removal_mode 0)
			)
			(polygon
				(pts
					(xy 134.366 -66.929) (xy 133.7564 -66.929) (xy 133.7564 -66.7766) (xy 134.366 -66.7766)
				)
			)
		)
	)
	(footprint ""
		(layer "F.Cu")
		(at 16.852392 -66.3956 180)
		(property "Reference" "R347"
			(at -0.927608 -1.53035 0)
			(unlocked yes)
			(layer "F.SilkS")
			(effects
				(font
					(size 0.635 0.4064)
					(thickness 0.1524)
				)
			)
		)
		(property "Value" "VAL*"
			(at 0.02032 2.13233 180)
			(unlocked yes)
			(layer "F.Fab")
			(hide yes)
			(effects
				(font
					(size 0.7874 0.5842)
					(thickness 0.1524)
				)
			)
		)
		(property "Tolerance" "TOL*"
			(at 0.044704 3.05435 180)
			(unlocked yes)
			(layer "Cmts.User")
			(hide yes)
			(effects
				(font
					(size 0.7874 0.5842)
					(thickness 0.1524)
				)
			)
		)
		(property "User Part Number" "PARTNUM*"
			(at 0.02032 4.024884 180)
			(unlocked yes)
			(layer "Cmts.User")
			(hide yes)
			(effects
				(font
					(size 0.7874 0.5842)
					(thickness 0.1524)
				)
			)
		)
		(property "Device Type" "RESISTOR-G155-100R0-J0,0OHM,-"
			(at 0.008382 1.210564 180)
			(unlocked yes)
			(layer "F.Fab")
			(hide yes)
			(effects
				(font
					(size 0.7874 0.5842)
					(thickness 0.1524)
				)
			)
		)
		(duplicate_pad_numbers_are_jumpers no)
		(fp_line
			(start 1.143 0.5588)
			(end 1.143 -0.5588)
			(stroke
				(width 0.1)
				(type default)
			)
			(layer "F.SilkS")
		)
		(fp_line
			(start 1.143 -0.5588)
			(end -1.143 -0.5588)
			(stroke
				(width 0.1)
				(type default)
			)
			(layer "F.SilkS")
		)
		(fp_line
			(start -1.143 0.5588)
			(end 1.143 0.5588)
			(stroke
				(width 0.1)
				(type default)
			)
			(layer "F.SilkS")
		)
		(fp_line
			(start -1.143 -0.5588)
			(end -1.143 0.5588)
			(stroke
				(width 0.1)
				(type default)
			)
			(layer "F.SilkS")
		)
		(fp_poly
			(pts
				(xy -1.143 0.5588) (xy 1.143 0.5588) (xy 1.143 -0.5588) (xy -1.143 -0.5588)
			)
			(stroke
				(width 0)
				(type default)
			)
			(fill no)
			(layer "F.CrtYd")
		)
		(fp_line
			(start 0.508 0.3048)
			(end 0.508 -0.3048)
			(stroke
				(width 0.1)
				(type default)
			)
			(layer "F.Fab")
		)
		(fp_line
			(start 0.508 -0.3048)
			(end -0.508 -0.3048)
			(stroke
				(width 0.1)
				(type default)
			)
			(layer "F.Fab")
		)
		(fp_line
			(start -0.508 0.3048)
			(end 0.508 0.3048)
			(stroke
				(width 0.1)
				(type default)
			)
			(layer "F.Fab")
		)
		(fp_line
			(start -0.508 -0.3048)
			(end -0.508 0.3048)
			(stroke
				(width 0.1)
				(type default)
			)
			(layer "F.Fab")
		)
		(pad "1" smd rect
			(at -0.5334 0 180)
			(size 0.7112 0.6096)
			(layers "F.Cu" "F.Mask" "F.Paste")
			(net "UNNAMED_8_ICP10100LGA10_I24_R_2")
		)
		(pad "2" smd rect
			(at 0.5334 0 180)
			(size 0.7112 0.6096)
			(layers "F.Cu" "F.Mask" "F.Paste")
			(net "XP1R8V_ICP10100")
		)
		(zone
			(layer "F.Cu")
			(hatch none 0.5)
			(connect_pads
				(clearance 0)
			)
			(min_thickness 0.25)
			(keepout
				(tracks allowed)
				(vias not_allowed)
				(pads allowed)
				(copperpour not_allowed)
				(footprints allowed)
			)
			(placement
				(enabled no)
				(sheetname "")
			)
			(fill
				(thermal_gap 0.5)
				(thermal_bridge_width 0.5)
				(island_removal_mode 0)
			)
			(polygon
				(pts
					(xy 16.928592 -66.7004) (xy 16.776192 -66.7004) (xy 16.776192 -66.0908) (xy 16.928592 -66.0908)
				)
			)
		)
		(zone
			(layer "F.Cu")
			(hatch none 0.5)
			(connect_pads
				(clearance 0)
			)
			(min_thickness 0.25)
			(keepout
				(tracks not_allowed)
				(vias allowed)
				(pads allowed)
				(copperpour not_allowed)
				(footprints allowed)
			)
			(placement
				(enabled no)
				(sheetname "")
			)
			(fill
				(thermal_gap 0.5)
				(thermal_bridge_width 0.5)
				(island_removal_mode 0)
			)
			(polygon
				(pts
					(xy 16.928592 -66.7004) (xy 16.776192 -66.7004) (xy 16.776192 -66.0908) (xy 16.928592 -66.0908)
				)
			)
		)
	)
)
